#ISCELL
  mstr_symbols intel_corp_bpage *
  *
#ISCELL
  w_power w_vcc_circle *
  page148_i10
#ISCELL
  mstr_standard offpage *
  page148_i12
#ISCELL
  mstr_standard offpage *
  page148_i13
#ISCELL
  w_power w_vcc_circle *
  page148_i14
#ISCELL
  w_power w_vcc_circle *
  page148_i15
#CELL
  mstr_discrete res *
  page148_i16
#ISCELL
  mstr_symbols p3v3_stby *
  page148_i18
#ISCELL
  w_power w_vcc_circle *
  page148_i19
#ISCELL
  mstr_symbols p3v3_stby *
  page148_i2
#CELL
  dev_discrete cap_a *
  page148_i20
#ISCELL
  mstr_symbols pvccio_cpu0 *
  page148_i21
#ISCELL
  mstr_symbols gnd *
  page148_i22
#ISCELL
  w_power w_vcc_circle *
  page148_i26
#ISCELL
  w_power w_vcc_circle *
  page148_i27
#CELL
  w_hdl ast2520a1-gp-gp *
  page148_i28
#CELL
  mstr_discrete res *
  page148_i29
#ISCELL
  mstr_symbols gnd *
  page148_i3
#ISCELL
  mstr_standard offpage *
  page148_i30
#ISCELL
  mstr_symbols p3v3_stby *
  page148_i4
#ISCELL
  w_power w_vcc_circle *
  page148_i6
#ISCELL
  w_power w_vcc_circle *
  page148_i7
#ISCELL
  w_power w_vcc_circle *
  page148_i8
#ISCELL
  w_power w_vcc_circle *
  page148_i9
